# T6G (Grand Teton) — schematic netlist excerpt (pin names and nets, part order shuffled) for the footprints in the layout excerpt that follows; sources: Cadence DE-HDL packaged netlist, KiCad conversion of 04192023_DAF0TMB3IC0_F0TG_MB_C_brd_V02_OCP.brd

J8067  PICOPROBE_BXA  DELTA-L 4.0 EMPTY  pkg TRIANG_LAUNCH_3PXB  page 229
  \1_p\  = DELTA_L_85_5INCH_IN3_DP
  \2_n\  = DELTA_L_85_5INCH_IN3_DN
  \3_g\  = DELTA_L_GND_1

(kicad_pcb
	(version 20260206)
	(generator "pcbnew")
	(generator_version "10.0")
	(general
		(thickness 1.6)
		(legacy_teardrops no)
	)
	(paper "A4")
	(title_block
		(title "04192023_DAF0TMB3IC0_F0TG_MB_C_brd_V02_OCP.brd")
		(comment 1 "Grand Teton / footprints 1753-1753 of 8354")
	)
	(layers
		(0 "F.Cu" signal "TOP")
		(4 "In1.Cu" signal "GND")
		(6 "In2.Cu" signal "IN1")
		(8 "In3.Cu" signal "GND1")
		(10 "In4.Cu" signal "IN2")
		(12 "In5.Cu" signal "GND2")
		(14 "In6.Cu" signal "IN3")
		(16 "In7.Cu" signal "GND3")
		(18 "In8.Cu" signal "VCC")
		(20 "In9.Cu" signal "VCC1")
		(22 "In10.Cu" signal "GND4")
		(24 "In11.Cu" signal "IN4")
		(26 "In12.Cu" signal "GND5")
		(28 "In13.Cu" signal "IN5")
		(30 "In14.Cu" signal "GND6")
		(32 "In15.Cu" signal "IN6")
		(34 "In16.Cu" signal "GND7")
		(2 "B.Cu" signal "BOTTOM")
		(9 "F.Adhes" user "F.Adhesive")
		(11 "B.Adhes" user "B.Adhesive")
		(13 "F.Paste" user "Package Geometry/Pastemask Top")
		(15 "B.Paste" user "Package Geometry/Pastemask Bottom")
		(5 "F.SilkS" user "Ref Des/Silkscreen Top")
		(7 "B.SilkS" user "Ref Des/Silkscreen Bottom")
		(1 "F.Mask" user "Board Geometry/Soldermask Top")
		(3 "B.Mask" user "Board Geometry/Soldermask Bottom")
		(17 "Dwgs.User" user "User.Drawings")
		(19 "Cmts.User" user "User.Comments")
		(21 "Eco1.User" user "User.Eco1")
		(23 "Eco2.User" user "User.Eco2")
		(25 "Edge.Cuts" user "Board Geometry/Outline")
		(27 "Margin" user)
		(31 "F.CrtYd" user "Package Geometry/Place Bound Top")
		(29 "B.CrtYd" user "Package Geometry/Place Bound Bottom")
		(35 "F.Fab" user "Ref Des/Assembly Top")
		(33 "B.Fab" user "Ref Des/Assembly Bottom")
	)
	(footprint ""
		(layer "F.Cu")
		(at 366.288574 0.002794 180)
		(property "Reference" "J8067"
			(at -4.710176 -2.058416 90)
			(unlocked yes)
			(layer "F.SilkS")
			(effects
				(font
					(size 0.7874 0.5842)
					(thickness 0.1524)
				)
				(justify left)
			)
		)
		(property "Value" ""
			(at 0 0 180)
			(layer "F.Fab")
			(effects
				(font
					(size 1.27 1.27)
				)
			)
		)
		(duplicate_pad_numbers_are_jumpers no)
		(fp_line
			(start 1.2192 2.06756)
			(end -1.2192 2.06756)
			(stroke
				(width 0.1524)
				(type default)
			)
			(layer "F.SilkS")
		)
		(fp_line
			(start 1.2192 -2.06756)
			(end 1.2192 2.06756)
			(stroke
				(width 0.1524)
				(type default)
			)
			(layer "F.SilkS")
		)
		(fp_line
			(start -1.2192 2.06756)
			(end -1.2192 -2.06756)
			(stroke
				(width 0.1524)
				(type default)
			)
			(layer "F.SilkS")
		)
		(fp_line
			(start -1.2192 -2.06756)
			(end 1.2192 -2.06756)
			(stroke
				(width 0.1524)
				(type default)
			)
			(layer "F.SilkS")
		)
		(pad "" np_thru_hole circle
			(at -2.8829 -1.27 90)
			(size 1.0414 1.0414)
			(drill 1.0414)
			(layers "*.Cu" "*.Mask")
			(clearance 0.381)
			(thermal_gap 0.381)
		)
		(pad "" np_thru_hole circle
			(at -2.8829 1.27 90)
			(size 1.0414 1.0414)
			(drill 1.0414)
			(layers "*.Cu" "*.Mask")
			(clearance 0.381)
			(thermal_gap 0.381)
		)
		(pad "" np_thru_hole circle
			(at 3.4671 -1.27 90)
			(size 1.0414 1.0414)
			(drill 1.0414)
			(layers "*.Cu" "*.Mask")
			(clearance 0.381)
			(thermal_gap 0.381)
		)
		(pad "" np_thru_hole circle
			(at 3.4671 1.27 90)
			(size 1.0414 1.0414)
			(drill 1.0414)
			(layers "*.Cu" "*.Mask")
			(clearance 0.381)
			(thermal_gap 0.381)
		)
		(pad "1" smd rect
			(at 0.8255 -0.249936 90)
			(size 0.3048 0.508)
			(layers "F.Cu" "F.Mask" "F.Paste")
			(net "DELTA_L_85_5INCH_IN3_DP")
		)
		(pad "2" smd rect
			(at 0.8255 0.249936 90)
			(size 0.3048 0.508)
			(layers "F.Cu" "F.Mask" "F.Paste")
			(net "DELTA_L_85_5INCH_IN3_DN")
		)
		(pad "3" smd circle
			(at 0 0 180)
			(size 0 0)
			(layers "F.Cu" "F.Mask" "F.Paste")
			(net "DELTA_L_GND_1")
		)
		(zone
			(layer "F.Cu")
			(hatch none 0.5)
			(connect_pads
				(clearance 0)
			)
			(min_thickness 0.25)
			(keepout
				(tracks not_allowed)
				(vias allowed)
				(pads allowed)
				(copperpour not_allowed)
				(footprints allowed)
			)
			(placement
				(enabled no)
				(sheetname "")
			)
			(fill
				(thermal_gap 0.5)
				(thermal_bridge_width 0.5)
				(island_removal_mode 0)
			)
			(polygon
				(pts
					(xy 365.170974 0.551434) (xy 365.170974 0.45593) (xy 365.767874 0.45593) (xy 365.767874 0.04953)
					(xy 365.170974 0.04953) (xy 365.170974 -0.043942) (xy 365.767874 -0.043942) (xy 365.767874 -0.450342)
					(xy 365.170974 -0.450342) (xy 365.170974 -0.545846) (xy 365.869474 -0.545846) (xy 365.869474 0.551434)
				)
			)
		)
		(zone
			(layers "F.Cu" "B.Cu" "In1.Cu" "In2.Cu" "In3.Cu" "In4.Cu" "In5.Cu" "In6.Cu"
				"In7.Cu" "In8.Cu" "In9.Cu" "In10.Cu" "In11.Cu" "In12.Cu" "In13.Cu" "In14.Cu"
				"In15.Cu" "In16.Cu"
			)
			(hatch none 0.5)
			(connect_pads
				(clearance 0)
			)
			(min_thickness 0.25)
			(keepout
				(tracks not_allowed)
				(vias allowed)
				(pads allowed)
				(copperpour not_allowed)
				(footprints allowed)
			)
			(placement
				(enabled no)
				(sheetname "")
			)
			(fill
				(thermal_gap 0.5)
				(thermal_bridge_width 0.5)
				(island_removal_mode 0)
			)
			(polygon
				(pts
					(arc
						(start 363.748574 -1.267206)
						(mid 361.894374 -1.267206)
						(end 363.748574 -1.267206)
					)
				)
			)
		)
		(zone
			(layers "F.Cu" "B.Cu" "In1.Cu" "In2.Cu" "In3.Cu" "In4.Cu" "In5.Cu" "In6.Cu"
				"In7.Cu" "In8.Cu" "In9.Cu" "In10.Cu" "In11.Cu" "In12.Cu" "In13.Cu" "In14.Cu"
				"In15.Cu" "In16.Cu"
			)
			(hatch none 0.5)
			(connect_pads
				(clearance 0)
			)
			(min_thickness 0.25)
			(keepout
				(tracks not_allowed)
				(vias allowed)
				(pads allowed)
				(copperpour not_allowed)
				(footprints allowed)
			)
			(placement
				(enabled no)
				(sheetname "")
			)
			(fill
				(thermal_gap 0.5)
				(thermal_bridge_width 0.5)
				(island_removal_mode 0)
			)
			(polygon
				(pts
					(arc
						(start 363.748574 1.272794)
						(mid 361.894374 1.272794)
						(end 363.748574 1.272794)
					)
				)
			)
		)
		(zone
			(layers "F.Cu" "B.Cu" "In1.Cu" "In2.Cu" "In3.Cu" "In4.Cu" "In5.Cu" "In6.Cu"
				"In7.Cu" "In8.Cu" "In9.Cu" "In10.Cu" "In11.Cu" "In12.Cu" "In13.Cu" "In14.Cu"
				"In15.Cu" "In16.Cu"
			)
			(hatch none 0.5)
			(connect_pads
				(clearance 0)
			)
			(min_thickness 0.25)
			(keepout
				(tracks not_allowed)
				(vias allowed)
				(pads allowed)
				(copperpour not_allowed)
				(footprints allowed)
			)
			(placement
				(enabled no)
				(sheetname "")
			)
			(fill
				(thermal_gap 0.5)
				(thermal_bridge_width 0.5)
				(island_removal_mode 0)
			)
			(polygon
				(pts
					(arc
						(start 370.098574 -1.267206)
						(mid 368.244374 -1.267206)
						(end 370.098574 -1.267206)
					)
				)
			)
		)
		(zone
			(layers "F.Cu" "B.Cu" "In1.Cu" "In2.Cu" "In3.Cu" "In4.Cu" "In5.Cu" "In6.Cu"
				"In7.Cu" "In8.Cu" "In9.Cu" "In10.Cu" "In11.Cu" "In12.Cu" "In13.Cu" "In14.Cu"
				"In15.Cu" "In16.Cu"
			)
			(hatch none 0.5)
			(connect_pads
				(clearance 0)
			)
			(min_thickness 0.25)
			(keepout
				(tracks not_allowed)
				(vias allowed)
				(pads allowed)
				(copperpour not_allowed)
				(footprints allowed)
			)
			(placement
				(enabled no)
				(sheetname "")
			)
			(fill
				(thermal_gap 0.5)
				(thermal_bridge_width 0.5)
				(island_removal_mode 0)
			)
			(polygon
				(pts
					(arc
						(start 370.098574 1.272794)
						(mid 368.244374 1.272794)
						(end 370.098574 1.272794)
					)
				)
			)
		)
	)
)
